(kicad_pcb
	(version 20260206)
	(generator "pcbnew")
	(generator_version "10.0")
	(general
		(thickness 1.6)
		(legacy_teardrops no)
	)
	(paper "A4")
	(title_block
		(title "peb — Lightning_PEB_BRD.brd")
		(comment 1 "Lightning (Wiwynn / Facebook NVMe JBOF) / footprints 2069-2075 of 2563")
	)
	(layers
		(0 "F.Cu" signal "TOP")
		(4 "In1.Cu" signal "L2GND")
		(6 "In2.Cu" signal "L3")
		(8 "In3.Cu" signal "L4VCC")
		(10 "In4.Cu" signal "L5VCC")
		(12 "In5.Cu" signal "L6")
		(14 "In6.Cu" signal "L7GND")
		(2 "B.Cu" signal "BOTTOM")
		(9 "F.Adhes" user "F.Adhesive")
		(11 "B.Adhes" user "B.Adhesive")
		(13 "F.Paste" user "Package Geometry/Pastemask Top")
		(15 "B.Paste" user "Package Geometry/Pastemask Bottom")
		(5 "F.SilkS" user "Ref Des/Silkscreen Top")
		(7 "B.SilkS" user "Ref Des/Silkscreen Bottom")
		(1 "F.Mask" user "Board Geometry/Soldermask Top")
		(3 "B.Mask" user "Board Geometry/Soldermask Bottom")
		(17 "Dwgs.User" user "User.Drawings")
		(19 "Cmts.User" user "User.Comments")
		(21 "Eco1.User" user "User.Eco1")
		(23 "Eco2.User" user "User.Eco2")
		(25 "Edge.Cuts" user "Board Geometry/Outline")
		(27 "Margin" user)
		(31 "F.CrtYd" user "Package Geometry/Place Bound Top")
		(29 "B.CrtYd" user "Package Geometry/Place Bound Bottom")
		(35 "F.Fab" user "Ref Des/Assembly Top")
		(33 "B.Fab" user "Ref Des/Assembly Bottom")
	)
	(footprint ""
		(layer "B.Cu")
		(at 83.230212 -186.545474)
		(property "Reference" "R3233"
			(at 0 0 0)
			(layer "B.SilkS")
			(hide yes)
			(effects
				(font
					(size 1.27 1.27)
				)
				(justify mirror)
			)
		)
		(property "Value" "0R2J-2-GP"
			(at -0.064008 -3.993896 0)
			(unlocked yes)
			(layer "B.Fab")
			(hide yes)
			(effects
				(font
					(size 1.016 1.016)
					(thickness 0.1524)
				)
				(justify mirror)
			)
		)
		(property "Device Type" "R402H16"
			(at -0.064008 -5.517896 0)
			(unlocked yes)
			(layer "B.Fab")
			(hide yes)
			(effects
				(font
					(size 1.016 1.016)
					(thickness 0.1524)
				)
				(justify mirror)
			)
		)
		(duplicate_pad_numbers_are_jumpers no)
		(fp_line
			(start -0.508 -0.9398)
			(end 0.508 -0.9398)
			(stroke
				(width 0.1524)
				(type default)
			)
			(layer "B.SilkS")
		)
		(fp_line
			(start 0.508 -0.9398)
			(end 0.508 0.9398)
			(stroke
				(width 0.1524)
				(type default)
			)
			(layer "B.SilkS")
		)
		(fp_rect
			(start 0.508 0.9398)
			(end -0.508 -0.9398)
			(stroke
				(width 0)
				(type default)
			)
			(fill no)
			(layer "B.CrtYd")
		)
		(fp_rect
			(start 0.508 0.9398)
			(end -0.508 -0.9398)
			(stroke
				(width 0)
				(type default)
			)
			(fill no)
			(layer "B.Fab")
		)
		(pad "1" smd custom
			(at 0 -0.4445 180)
			(size 0.1397 0.1397)
			(layers "B.Cu" "B.Mask" "B.Paste")
			(net "SSD_PERST_Y10")
			(options
				(clearance outline)
				(anchor circle)
			)
			(primitives
				(gr_poly
					(pts
						(arc
							(start -0.1778 0.2794)
							(mid -0.249642 0.249642)
							(end -0.2794 0.1778)
						)
						(arc
							(start -0.2794 -0.1778)
							(mid -0.249642 -0.249642)
							(end -0.1778 -0.2794)
						)
						(arc
							(start 0.1778 -0.2794)
							(mid 0.249642 -0.249642)
							(end 0.2794 -0.1778)
						)
						(arc
							(start 0.2794 0.1778)
							(mid 0.249642 0.249642)
							(end 0.1778 0.2794)
						)
					)
					(width 0)
					(fill yes)
				)
			)
		)
		(pad "2" smd custom
			(at 0 0.4445 180)
			(size 0.1397 0.1397)
			(layers "B.Cu" "B.Mask" "B.Paste")
			(net "SSD_PERST#10_R")
			(options
				(clearance outline)
				(anchor circle)
			)
			(primitives
				(gr_poly
					(pts
						(arc
							(start -0.1778 0.2794)
							(mid -0.249642 0.249642)
							(end -0.2794 0.1778)
						)
						(arc
							(start -0.2794 -0.1778)
							(mid -0.249642 -0.249642)
							(end -0.1778 -0.2794)
						)
						(arc
							(start 0.1778 -0.2794)
							(mid 0.249642 -0.249642)
							(end 0.2794 -0.1778)
						)
						(arc
							(start 0.2794 0.1778)
							(mid 0.249642 0.249642)
							(end 0.1778 0.2794)
						)
					)
					(width 0)
					(fill yes)
				)
			)
		)
	)
	(footprint ""
		(layer "B.Cu")
		(at 68.961 -42.164 -90)
		(property "Reference" "PR28"
			(at 0 0 90)
			(layer "B.SilkS")
			(hide yes)
			(effects
				(font
					(size 1.27 1.27)
				)
				(justify mirror)
			)
		)
		(property "Value" "3D01R5F-GP"
			(at 0 -8.9535 270)
			(unlocked yes)
			(layer "B.Fab")
			(hide yes)
			(effects
				(font
					(size 1.27 1.016)
					(thickness 0.1524)
				)
				(justify mirror)
			)
		)
		(property "Device Type" "R805H24"
			(at 0 -10.6299 270)
			(unlocked yes)
			(layer "B.Fab")
			(hide yes)
			(effects
				(font
					(size 1.27 1.016)
					(thickness 0.1524)
				)
				(justify mirror)
			)
		)
		(duplicate_pad_numbers_are_jumpers no)
		(fp_line
			(start -0.889 1.7018)
			(end -0.889 -0.508)
			(stroke
				(width 0.1524)
				(type default)
			)
			(layer "B.SilkS")
		)
		(fp_line
			(start 0.889 1.7018)
			(end -0.889 1.7018)
			(stroke
				(width 0.1524)
				(type default)
			)
			(layer "B.SilkS")
		)
		(fp_line
			(start 0.889 0.0762)
			(end 0.889 1.7018)
			(stroke
				(width 0.1524)
				(type default)
			)
			(layer "B.SilkS")
		)
		(fp_line
			(start -0.889 -1.7018)
			(end -0.889 -0.381)
			(stroke
				(width 0.1524)
				(type default)
			)
			(layer "B.SilkS")
		)
		(fp_line
			(start -0.889 -1.7018)
			(end 0.889 -1.7018)
			(stroke
				(width 0.1524)
				(type default)
			)
			(layer "B.SilkS")
		)
		(fp_line
			(start 0.889 -1.7018)
			(end 0.889 0.2794)
			(stroke
				(width 0.1524)
				(type default)
			)
			(layer "B.SilkS")
		)
		(fp_poly
			(pts
				(xy -0.9652 -1.778) (xy -0.9652 1.778) (xy 0.9652 1.778) (xy 0.9652 -1.778)
			)
			(stroke
				(width 0)
				(type default)
			)
			(fill no)
			(layer "B.CrtYd")
		)
		(fp_rect
			(start 0.9652 1.778)
			(end -0.9652 -1.778)
			(stroke
				(width 0)
				(type default)
			)
			(fill no)
			(layer "B.Fab")
		)
		(pad "1" smd rect
			(at 0 -0.9652 90)
			(size 1.397 1.143)
			(layers "B.Cu" "B.Mask" "B.Paste")
			(net "P3V3_STBY_SNB")
		)
		(pad "2" smd rect
			(at 0 0.9652 90)
			(size 1.397 1.143)
			(layers "B.Cu" "B.Mask" "B.Paste")
			(net "GND")
		)
	)
	(footprint ""
		(layer "B.Cu")
		(at 336.836512 -172.432218)
		(property "Reference" "R4156"
			(at 0 0 0)
			(layer "B.SilkS")
			(hide yes)
			(effects
				(font
					(size 1.27 1.27)
				)
				(justify mirror)
			)
		)
		(property "Value" "4K7R2F-GP"
			(at -0.064008 -3.993896 0)
			(unlocked yes)
			(layer "B.Fab")
			(hide yes)
			(effects
				(font
					(size 1.016 1.016)
					(thickness 0.1524)
				)
				(justify mirror)
			)
		)
		(property "Device Type" "R402H16"
			(at -0.064008 -5.517896 0)
			(unlocked yes)
			(layer "B.Fab")
			(hide yes)
			(effects
				(font
					(size 1.016 1.016)
					(thickness 0.1524)
				)
				(justify mirror)
			)
		)
		(duplicate_pad_numbers_are_jumpers no)
		(fp_line
			(start -0.508 -0.9398)
			(end 0.508 -0.9398)
			(stroke
				(width 0.1524)
				(type default)
			)
			(layer "B.SilkS")
		)
		(fp_line
			(start 0.508 -0.9398)
			(end 0.508 0.9398)
			(stroke
				(width 0.1524)
				(type default)
			)
			(layer "B.SilkS")
		)
		(fp_rect
			(start 0.508 0.9398)
			(end -0.508 -0.9398)
			(stroke
				(width 0)
				(type default)
			)
			(fill no)
			(layer "B.CrtYd")
		)
		(fp_rect
			(start 0.508 0.9398)
			(end -0.508 -0.9398)
			(stroke
				(width 0)
				(type default)
			)
			(fill no)
			(layer "B.Fab")
		)
		(pad "1" smd custom
			(at 0 -0.4445 180)
			(size 0.1397 0.1397)
			(layers "B.Cu" "B.Mask" "B.Paste")
			(net "SSD_PRSNT#9")
			(options
				(clearance outline)
				(anchor circle)
			)
			(primitives
				(gr_poly
					(pts
						(arc
							(start -0.1778 0.2794)
							(mid -0.249642 0.249642)
							(end -0.2794 0.1778)
						)
						(arc
							(start -0.2794 -0.1778)
							(mid -0.249642 -0.249642)
							(end -0.1778 -0.2794)
						)
						(arc
							(start 0.1778 -0.2794)
							(mid 0.249642 -0.249642)
							(end 0.2794 -0.1778)
						)
						(arc
							(start 0.2794 0.1778)
							(mid 0.249642 0.249642)
							(end 0.1778 0.2794)
						)
					)
					(width 0)
					(fill yes)
				)
			)
		)
		(pad "2" smd custom
			(at 0 0.4445 180)
			(size 0.1397 0.1397)
			(layers "B.Cu" "B.Mask" "B.Paste")
			(net "P3V3_STBY")
			(options
				(clearance outline)
				(anchor circle)
			)
			(primitives
				(gr_poly
					(pts
						(arc
							(start -0.1778 0.2794)
							(mid -0.249642 0.249642)
							(end -0.2794 0.1778)
						)
						(arc
							(start -0.2794 -0.1778)
							(mid -0.249642 -0.249642)
							(end -0.1778 -0.2794)
						)
						(arc
							(start 0.1778 -0.2794)
							(mid 0.249642 -0.249642)
							(end 0.2794 -0.1778)
						)
						(arc
							(start 0.2794 0.1778)
							(mid 0.249642 0.249642)
							(end 0.1778 0.2794)
						)
					)
					(width 0)
					(fill yes)
				)
			)
		)
	)
	(footprint ""
		(layer "B.Cu")
		(at 212.598 -197.231 180)
		(property "Reference" "R3241"
			(at 0 0 0)
			(layer "B.SilkS")
			(hide yes)
			(effects
				(font
					(size 1.27 1.27)
				)
				(justify mirror)
			)
		)
		(property "Value" "0R2J-2-GP"
			(at -0.064008 -3.993896 180)
			(unlocked yes)
			(layer "B.Fab")
			(hide yes)
			(effects
				(font
					(size 1.016 1.016)
					(thickness 0.1524)
				)
				(justify mirror)
			)
		)
		(property "Device Type" "R402H16"
			(at -0.064008 -5.517896 180)
			(unlocked yes)
			(layer "B.Fab")
			(hide yes)
			(effects
				(font
					(size 1.016 1.016)
					(thickness 0.1524)
				)
				(justify mirror)
			)
		)
		(duplicate_pad_numbers_are_jumpers no)
		(fp_line
			(start 0.508 -0.9398)
			(end 0.508 0.9398)
			(stroke
				(width 0.1524)
				(type default)
			)
			(layer "B.SilkS")
		)
		(fp_line
			(start -0.508 -0.9398)
			(end 0.508 -0.9398)
			(stroke
				(width 0.1524)
				(type default)
			)
			(layer "B.SilkS")
		)
		(fp_rect
			(start 0.508 0.9398)
			(end -0.508 -0.9398)
			(stroke
				(width 0)
				(type default)
			)
			(fill no)
			(layer "B.CrtYd")
		)
		(fp_rect
			(start 0.508 0.9398)
			(end -0.508 -0.9398)
			(stroke
				(width 0)
				(type default)
			)
			(fill no)
			(layer "B.Fab")
		)
		(pad "1" smd custom
			(at 0 -0.4445)
			(size 0.1397 0.1397)
			(layers "B.Cu" "B.Mask" "B.Paste")
			(net "BMC_SSD_RST#13")
			(options
				(clearance outline)
				(anchor circle)
			)
			(primitives
				(gr_poly
					(pts
						(arc
							(start -0.1778 0.2794)
							(mid -0.249642 0.249642)
							(end -0.2794 0.1778)
						)
						(arc
							(start -0.2794 -0.1778)
							(mid -0.249642 -0.249642)
							(end -0.1778 -0.2794)
						)
						(arc
							(start 0.1778 -0.2794)
							(mid 0.249642 -0.249642)
							(end 0.2794 -0.1778)
						)
						(arc
							(start 0.2794 0.1778)
							(mid 0.249642 0.249642)
							(end 0.1778 0.2794)
						)
					)
					(width 0)
					(fill yes)
				)
			)
		)
		(pad "2" smd custom
			(at 0 0.4445)
			(size 0.1397 0.1397)
			(layers "B.Cu" "B.Mask" "B.Paste")
			(net "BMC_SSD_RST#0_A13")
			(options
				(clearance outline)
				(anchor circle)
			)
			(primitives
				(gr_poly
					(pts
						(arc
							(start -0.1778 0.2794)
							(mid -0.249642 0.249642)
							(end -0.2794 0.1778)
						)
						(arc
							(start -0.2794 -0.1778)
							(mid -0.249642 -0.249642)
							(end -0.1778 -0.2794)
						)
						(arc
							(start 0.1778 -0.2794)
							(mid 0.249642 -0.249642)
							(end 0.2794 -0.1778)
						)
						(arc
							(start 0.2794 0.1778)
							(mid 0.249642 0.249642)
							(end 0.1778 0.2794)
						)
					)
					(width 0)
					(fill yes)
				)
			)
		)
	)
	(footprint ""
		(layer "B.Cu")
		(at 25.4508 -69.96684 90)
		(property "Reference" "R459"
			(at 0 0 90)
			(layer "B.SilkS")
			(hide yes)
			(effects
				(font
					(size 1.27 1.27)
				)
				(justify mirror)
			)
		)
		(property "Value" "10KR2F-2-GP"
			(at -0.064008 -3.993896 90)
			(unlocked yes)
			(layer "B.Fab")
			(hide yes)
			(effects
				(font
					(size 1.016 1.016)
					(thickness 0.1524)
				)
				(justify mirror)
			)
		)
		(property "Device Type" "R402H16"
			(at -0.064008 -5.517896 90)
			(unlocked yes)
			(layer "B.Fab")
			(hide yes)
			(effects
				(font
					(size 1.016 1.016)
					(thickness 0.1524)
				)
				(justify mirror)
			)
		)
		(duplicate_pad_numbers_are_jumpers no)
		(fp_line
			(start 0.508 -0.9398)
			(end 0.508 0.9398)
			(stroke
				(width 0.1524)
				(type default)
			)
			(layer "B.SilkS")
		)
		(fp_line
			(start -0.508 -0.9398)
			(end 0.508 -0.9398)
			(stroke
				(width 0.1524)
				(type default)
			)
			(layer "B.SilkS")
		)
		(fp_rect
			(start 0.508 0.9398)
			(end -0.508 -0.9398)
			(stroke
				(width 0)
				(type default)
			)
			(fill no)
			(layer "B.CrtYd")
		)
		(fp_rect
			(start 0.508 0.9398)
			(end -0.508 -0.9398)
			(stroke
				(width 0)
				(type default)
			)
			(fill no)
			(layer "B.Fab")
		)
		(pad "1" smd custom
			(at 0 -0.4445 270)
			(size 0.1397 0.1397)
			(layers "B.Cu" "B.Mask" "B.Paste")
			(net "GND")
			(options
				(clearance outline)
				(anchor circle)
			)
			(primitives
				(gr_poly
					(pts
						(arc
							(start -0.1778 0.2794)
							(mid -0.249642 0.249642)
							(end -0.2794 0.1778)
						)
						(arc
							(start -0.2794 -0.1778)
							(mid -0.249642 -0.249642)
							(end -0.1778 -0.2794)
						)
						(arc
							(start 0.1778 -0.2794)
							(mid 0.249642 -0.249642)
							(end 0.2794 -0.1778)
						)
						(arc
							(start 0.2794 0.1778)
							(mid 0.249642 0.249642)
							(end 0.1778 0.2794)
						)
					)
					(width 0)
					(fill yes)
				)
			)
		)
		(pad "2" smd custom
			(at 0 0.4445 270)
			(size 0.1397 0.1397)
			(layers "B.Cu" "B.Mask" "B.Paste")
			(net "RMII_BMC_TX_EN")
			(options
				(clearance outline)
				(anchor circle)
			)
			(primitives
				(gr_poly
					(pts
						(arc
							(start -0.1778 0.2794)
							(mid -0.249642 0.249642)
							(end -0.2794 0.1778)
						)
						(arc
							(start -0.2794 -0.1778)
							(mid -0.249642 -0.249642)
							(end -0.1778 -0.2794)
						)
						(arc
							(start 0.1778 -0.2794)
							(mid 0.249642 -0.249642)
							(end 0.2794 -0.1778)
						)
						(arc
							(start 0.2794 0.1778)
							(mid 0.249642 0.249642)
							(end 0.1778 0.2794)
						)
					)
					(width 0)
					(fill yes)
				)
			)
		)
	)
	(footprint ""
		(layer "B.Cu")
		(at 227.457 -196.977)
		(property "Reference" "U76"
			(at 0 0 0)
			(layer "B.SilkS")
			(hide yes)
			(effects
				(font
					(size 1.27 1.27)
				)
				(justify mirror)
			)
		)
		(property "Value" "SN74LVC1G08DCKR-GP"
			(at 2.3368 -8.6868 0)
			(unlocked yes)
			(layer "B.Fab")
			(hide yes)
			(effects
				(font
					(size 1.016 1.016)
					(thickness 0.1524)
				)
				(justify mirror)
			)
		)
		(property "Device Type" "SC70-5H44"
			(at 2.3114 -10.414 0)
			(unlocked yes)
			(layer "B.Fab")
			(hide yes)
			(effects
				(font
					(size 1.016 1.016)
					(thickness 0.1524)
				)
				(justify mirror)
			)
		)
		(duplicate_pad_numbers_are_jumpers no)
		(fp_line
			(start -1.3843 -1.8034)
			(end -1.3843 -1.1176)
			(stroke
				(width 0.3302)
				(type default)
			)
			(layer "B.SilkS")
		)
		(fp_line
			(start -1.27 -1.7018)
			(end -1.27 1.7018)
			(stroke
				(width 0.1524)
				(type default)
			)
			(layer "B.SilkS")
		)
		(fp_line
			(start -1.27 1.7018)
			(end 1.27 1.7018)
			(stroke
				(width 0.1524)
				(type default)
			)
			(layer "B.SilkS")
		)
		(fp_line
			(start -0.6604 -1.8034)
			(end -1.3843 -1.8034)
			(stroke
				(width 0.3302)
				(type default)
			)
			(layer "B.SilkS")
		)
		(fp_line
			(start 1.27 -1.7018)
			(end -1.27 -1.7018)
			(stroke
				(width 0.1524)
				(type default)
			)
			(layer "B.SilkS")
		)
		(fp_line
			(start 1.27 1.7018)
			(end 1.27 -1.7018)
			(stroke
				(width 0.1524)
				(type default)
			)
			(layer "B.SilkS")
		)
		(fp_rect
			(start 1.524 1.9558)
			(end -1.524 -1.9558)
			(stroke
				(width 0)
				(type default)
			)
			(fill no)
			(layer "B.CrtYd")
		)
		(fp_poly
			(pts
				(xy 1.524 -1.9558) (xy -1.524 -1.9558) (xy -1.524 1.9558) (xy 1.524 1.9558)
			)
			(stroke
				(width 0)
				(type default)
			)
			(fill no)
			(layer "B.Fab")
		)
		(pad "1" smd rect
			(at -0.65024 -0.8255 180)
			(size 0.4064 1.2192)
			(layers "B.Cu" "B.Mask" "B.Paste")
			(net "BMC_SSD_RST#0_A12")
		)
		(pad "2" smd rect
			(at 0 -0.8255 180)
			(size 0.4064 1.2192)
			(layers "B.Cu" "B.Mask" "B.Paste")
			(net "SSD_PERST#0_B12")
		)
		(pad "3" smd rect
			(at 0.65024 -0.8255 180)
			(size 0.4064 1.2192)
			(layers "B.Cu" "B.Mask" "B.Paste")
			(net "GND")
		)
		(pad "4" smd rect
			(at 0.65024 0.8255 180)
			(size 0.4064 1.2192)
			(layers "B.Cu" "B.Mask" "B.Paste")
			(net "SSD_PERST_Y12")
		)
		(pad "5" smd rect
			(at -0.65024 0.8255 180)
			(size 0.4064 1.2192)
			(layers "B.Cu" "B.Mask" "B.Paste")
			(net "P3V3_STBY")
		)
	)
	(footprint ""
		(layer "B.Cu")
		(at 57.032652 -118.4402 -90)
		(property "Reference" "R243"
			(at 0 0 90)
			(layer "B.SilkS")
			(hide yes)
			(effects
				(font
					(size 1.27 1.27)
				)
				(justify mirror)
			)
		)
		(property "Value" "0R2J-2-GP"
			(at -0.064008 -3.993896 270)
			(unlocked yes)
			(layer "B.Fab")
			(hide yes)
			(effects
				(font
					(size 1.016 1.016)
					(thickness 0.1524)
				)
				(justify mirror)
			)
		)
		(property "Device Type" "R402H16"
			(at -0.064008 -5.517896 270)
			(unlocked yes)
			(layer "B.Fab")
			(hide yes)
			(effects
				(font
					(size 1.016 1.016)
					(thickness 0.1524)
				)
				(justify mirror)
			)
		)
		(duplicate_pad_numbers_are_jumpers no)
		(fp_line
			(start -0.508 -0.9398)
			(end 0.508 -0.9398)
			(stroke
				(width 0.1524)
				(type default)
			)
			(layer "B.SilkS")
		)
		(fp_line
			(start 0.508 -0.9398)
			(end 0.508 0.9398)
			(stroke
				(width 0.1524)
				(type default)
			)
			(layer "B.SilkS")
		)
		(fp_rect
			(start 0.508 0.9398)
			(end -0.508 -0.9398)
			(stroke
				(width 0)
				(type default)
			)
			(fill no)
			(layer "B.CrtYd")
		)
		(fp_rect
			(start 0.508 0.9398)
			(end -0.508 -0.9398)
			(stroke
				(width 0)
				(type default)
			)
			(fill no)
			(layer "B.Fab")
		)
		(pad "1" smd custom
			(at 0 -0.4445 90)
			(size 0.1397 0.1397)
			(layers "B.Cu" "B.Mask" "B.Paste")
			(net "BMC_I2C3_MINI3_SDA_S")
			(options
				(clearance outline)
				(anchor circle)
			)
			(primitives
				(gr_poly
					(pts
						(arc
							(start -0.1778 0.2794)
							(mid -0.249642 0.249642)
							(end -0.2794 0.1778)
						)
						(arc
							(start -0.2794 -0.1778)
							(mid -0.249642 -0.249642)
							(end -0.1778 -0.2794)
						)
						(arc
							(start 0.1778 -0.2794)
							(mid 0.249642 -0.249642)
							(end 0.2794 -0.1778)
						)
						(arc
							(start 0.2794 0.1778)
							(mid 0.249642 0.249642)
							(end 0.1778 0.2794)
						)
					)
					(width 0)
					(fill yes)
				)
			)
		)
		(pad "2" smd custom
			(at 0 0.4445 90)
			(size 0.1397 0.1397)
			(layers "B.Cu" "B.Mask" "B.Paste")
			(net "BMC0_SMB3_DAT")
			(options
				(clearance outline)
				(anchor circle)
			)
			(primitives
				(gr_poly
					(pts
						(arc
							(start -0.1778 0.2794)
							(mid -0.249642 0.249642)
							(end -0.2794 0.1778)
						)
						(arc
							(start -0.2794 -0.1778)
							(mid -0.249642 -0.249642)
							(end -0.1778 -0.2794)
						)
						(arc
							(start 0.1778 -0.2794)
							(mid 0.249642 -0.249642)
							(end 0.2794 -0.1778)
						)
						(arc
							(start 0.2794 0.1778)
							(mid 0.249642 0.249642)
							(end 0.1778 0.2794)
						)
					)
					(width 0)
					(fill yes)
				)
			)
		)
	)
)
